# TIMECARD (Time Appliance Project (Time Card)) — schematic netlist excerpt (pin names and nets, part order shuffled) for the footprints in the layout excerpt that follows; sources: Cadence DE-HDL packaged netlist, KiCad conversion of R4006-B0001-02_R01.brd

R38  RESISTOR  4.42KOHM 1%  pkg SMC_0402R_H016  page 28 : \1\ = XP3R3V_FB_R_TO_AGND ; \2\ = XP3R3V_AGND
C63  CAPACITOR  0.1UF 25V 10%  pkg SMC_0402R_H022  page 21 : \1\ = XP5R0V_USB_CONN ; \2\ = SG
TP25  TP_PIONT  pkg TP010CT020B030_PTH  page 25 : \1\ = RGB_LED_SHUTDOWN_N

(kicad_pcb
	(version 20260206)
	(generator "pcbnew")
	(generator_version "10.0")
	(general
		(thickness 1.6)
		(legacy_teardrops no)
	)
	(paper "A4")
	(title_block
		(title "timecard-production-celestica-r4006 — R4006-B0001-02_R01.brd")
		(comment 1 "Time Appliance Project (Time Card) / footprints 667-669 of 1113")
	)
	(layers
		(0 "F.Cu" signal "TOP")
		(4 "In1.Cu" signal "L02_GND1")
		(6 "In2.Cu" signal "L03_SIG1")
		(8 "In3.Cu" signal "L04_GND2")
		(10 "In4.Cu" signal "L05_VCC1")
		(12 "In5.Cu" signal "L06_VCC2")
		(14 "In6.Cu" signal "L07_GND3")
		(16 "In7.Cu" signal "L08_SIG2")
		(18 "In8.Cu" signal "L09_GND4")
		(2 "B.Cu" signal "BOTTOM")
		(9 "F.Adhes" user "F.Adhesive")
		(11 "B.Adhes" user "B.Adhesive")
		(13 "F.Paste" user "Package Geometry/Pastemask Top")
		(15 "B.Paste" user "Package Geometry/Pastemask Bottom")
		(5 "F.SilkS" user "Ref Des/Silkscreen Top")
		(7 "B.SilkS" user "Ref Des/Silkscreen Bottom")
		(1 "F.Mask" user "Board Geometry/Soldermask Top")
		(3 "B.Mask" user "Board Geometry/Soldermask Bottom")
		(17 "Dwgs.User" user "User.Drawings")
		(19 "Cmts.User" user "User.Comments")
		(21 "Eco1.User" user "User.Eco1")
		(23 "Eco2.User" user "User.Eco2")
		(25 "Edge.Cuts" user "Board Geometry/Outline")
		(27 "Margin" user)
		(31 "F.CrtYd" user "Package Geometry/Place Bound Top")
		(29 "B.CrtYd" user "Package Geometry/Place Bound Bottom")
		(35 "F.Fab" user "Ref Des/Assembly Top")
		(33 "B.Fab" user "Ref Des/Assembly Bottom")
	)
	(footprint ""
		(layer "F.Cu")
		(at 109.22 -98.171)
		(property "Reference" "TP25"
			(at -0.9144 1.04775 0)
			(unlocked yes)
			(layer "F.SilkS")
			(effects
				(font
					(size 0.635 0.4064)
					(thickness 0.1524)
				)
				(justify left)
			)
		)
		(property "Value" ""
			(at 0 0 0)
			(layer "F.Fab")
			(effects
				(font
					(size 1.27 1.27)
				)
			)
		)
		(property "Device Type" "TP_PIONT-TP010CT020B030_PTH-TPA"
			(at -1.341882 0.996696 0)
			(unlocked yes)
			(layer "F.Fab")
			(hide yes)
			(effects
				(font
					(size 0.7874 0.5842)
					(thickness 0.000001)
				)
				(justify left)
			)
		)
		(duplicate_pad_numbers_are_jumpers no)
		(fp_poly
			(pts
				(arc
					(start 0.889 0)
					(mid -0.889 0)
					(end 0.889 0)
				)
			)
			(stroke
				(width 0)
				(type default)
			)
			(fill no)
			(layer "B.CrtYd")
		)
		(fp_poly
			(pts
				(arc
					(start 0.889 0)
					(mid -0.889 0)
					(end 0.889 0)
				)
			)
			(stroke
				(width 0)
				(type default)
			)
			(fill no)
			(layer "F.CrtYd")
		)
		(pad "1" thru_hole circle
			(at 0 0)
			(size 0.508 0.508)
			(drill 0.254)
			(layers "*.Cu" "*.Mask")
			(remove_unused_layers no)
			(net "RGB_LED_SHUTDOWN_N")
			(clearance 0.1016)
			(padstack
				(mode front_inner_back)
				(layer "Inner"
					(shape circle)
					(size 0.508 0.508)
					(clearance 0.1016)
				)
				(layer "B.Cu"
					(shape circle)
					(size 0.762 0.762)
					(clearance -0.0254)
				)
			)
		)
	)
	(footprint ""
		(layer "F.Cu")
		(at 89.281 -96.012 180)
		(property "Reference" "R38"
			(at -1.651 -2.32537 0)
			(unlocked yes)
			(layer "F.SilkS")
			(effects
				(font
					(size 0.7874 0.5842)
					(thickness 0.1524)
				)
			)
		)
		(property "Value" "VAL*"
			(at 0.02032 2.13233 180)
			(unlocked yes)
			(layer "F.Fab")
			(hide yes)
			(effects
				(font
					(size 0.7874 0.5842)
					(thickness 0.1524)
				)
			)
		)
		(property "Tolerance" "TOL*"
			(at 0.044704 3.05435 180)
			(unlocked yes)
			(layer "Cmts.User")
			(hide yes)
			(effects
				(font
					(size 0.7874 0.5842)
					(thickness 0.1524)
				)
			)
		)
		(property "User Part Number" "PARTNUM*"
			(at 0.02032 4.024884 180)
			(unlocked yes)
			(layer "Cmts.User")
			(hide yes)
			(effects
				(font
					(size 0.7874 0.5842)
					(thickness 0.1524)
				)
			)
		)
		(property "Device Type" "RESISTOR-G155-04421-01,4.42KOHA"
			(at 0.008382 1.210564 180)
			(unlocked yes)
			(layer "F.Fab")
			(hide yes)
			(effects
				(font
					(size 0.7874 0.5842)
					(thickness 0.1524)
				)
			)
		)
		(duplicate_pad_numbers_are_jumpers no)
		(fp_line
			(start 1.143 0.5588)
			(end 1.143 -0.5588)
			(stroke
				(width 0.1)
				(type default)
			)
			(layer "F.SilkS")
		)
		(fp_line
			(start 1.143 -0.5588)
			(end -1.143 -0.5588)
			(stroke
				(width 0.1)
				(type default)
			)
			(layer "F.SilkS")
		)
		(fp_line
			(start -1.143 0.5588)
			(end 1.143 0.5588)
			(stroke
				(width 0.1)
				(type default)
			)
			(layer "F.SilkS")
		)
		(fp_line
			(start -1.143 -0.5588)
			(end -1.143 0.5588)
			(stroke
				(width 0.1)
				(type default)
			)
			(layer "F.SilkS")
		)
		(fp_rect
			(start -1.143 -0.5588)
			(end 1.143 0.5588)
			(stroke
				(width 0)
				(type default)
			)
			(fill no)
			(layer "F.CrtYd")
		)
		(fp_line
			(start 0.508 0.3048)
			(end 0.508 -0.3048)
			(stroke
				(width 0.1)
				(type default)
			)
			(layer "F.Fab")
		)
		(fp_line
			(start 0.508 -0.3048)
			(end -0.508 -0.3048)
			(stroke
				(width 0.1)
				(type default)
			)
			(layer "F.Fab")
		)
		(fp_line
			(start -0.508 0.3048)
			(end 0.508 0.3048)
			(stroke
				(width 0.1)
				(type default)
			)
			(layer "F.Fab")
		)
		(fp_line
			(start -0.508 -0.3048)
			(end -0.508 0.3048)
			(stroke
				(width 0.1)
				(type default)
			)
			(layer "F.Fab")
		)
		(pad "1" smd rect
			(at -0.5334 0 180)
			(size 0.7112 0.6096)
			(layers "F.Cu" "F.Mask" "F.Paste")
			(net "XP3R3V_FB_R_TO_AGND")
		)
		(pad "2" smd rect
			(at 0.5334 0 180)
			(size 0.7112 0.6096)
			(layers "F.Cu" "F.Mask" "F.Paste")
			(net "XP3R3V_AGND")
		)
		(zone
			(layer "F.Cu")
			(hatch none 0.5)
			(connect_pads
				(clearance 0)
			)
			(min_thickness 0.25)
			(keepout
				(tracks allowed)
				(vias not_allowed)
				(pads allowed)
				(copperpour not_allowed)
				(footprints allowed)
			)
			(placement
				(enabled no)
				(sheetname "")
			)
			(fill
				(thermal_gap 0.5)
				(thermal_bridge_width 0.5)
				(island_removal_mode 0)
			)
			(polygon
				(pts
					(xy 89.3572 -95.7072) (xy 89.3572 -96.3168) (xy 89.2048 -96.3168) (xy 89.2048 -95.7072)
				)
			)
		)
	)
	(footprint ""
		(layer "F.Cu")
		(at 159.7406 -50.590196 -90)
		(property "Reference" "C63"
			(at -1.098804 3.11023 90)
			(unlocked yes)
			(layer "F.SilkS")
			(effects
				(font
					(size 0.7874 0.5842)
					(thickness 0.1524)
				)
			)
		)
		(property "Value" "VAL*"
			(at 0.0762 2.067306 270)
			(unlocked yes)
			(layer "F.Fab")
			(hide yes)
			(effects
				(font
					(size 0.7874 0.5842)
					(thickness 0.1524)
				)
			)
		)
		(property "Tolerance" "TOL*"
			(at 0.0762 3.032506 270)
			(unlocked yes)
			(layer "Cmts.User")
			(hide yes)
			(effects
				(font
					(size 0.7874 0.5842)
					(thickness 0.1524)
				)
			)
		)
		(property "User Part Number" "PARTNUM*"
			(at 0.1016 4.023106 270)
			(unlocked yes)
			(layer "Cmts.User")
			(hide yes)
			(effects
				(font
					(size 0.7874 0.5842)
					(thickness 0.1524)
				)
			)
		)
		(property "Device Type" "CAPACITOR-G105-0B104-EK,0.1UF,A"
			(at 0.0508 1.127506 270)
			(unlocked yes)
			(layer "F.Fab")
			(hide yes)
			(effects
				(font
					(size 0.7874 0.5842)
					(thickness 0.1524)
				)
			)
		)
		(duplicate_pad_numbers_are_jumpers no)
		(fp_line
			(start -1.143 0.5588)
			(end 1.143 0.5588)
			(stroke
				(width 0.1)
				(type default)
			)
			(layer "F.SilkS")
		)
		(fp_line
			(start 1.143 0.5588)
			(end 1.143 -0.5588)
			(stroke
				(width 0.1)
				(type default)
			)
			(layer "F.SilkS")
		)
		(fp_line
			(start -1.143 -0.5588)
			(end -1.143 0.5588)
			(stroke
				(width 0.1)
				(type default)
			)
			(layer "F.SilkS")
		)
		(fp_line
			(start 1.143 -0.5588)
			(end -1.143 -0.5588)
			(stroke
				(width 0.1)
				(type default)
			)
			(layer "F.SilkS")
		)
		(fp_rect
			(start 1.143 -0.5588)
			(end -1.143 0.5588)
			(stroke
				(width 0)
				(type default)
			)
			(fill no)
			(layer "F.CrtYd")
		)
		(fp_line
			(start -0.508 0.3048)
			(end 0.508 0.3048)
			(stroke
				(width 0.1)
				(type default)
			)
			(layer "F.Fab")
		)
		(fp_line
			(start 0.508 0.3048)
			(end 0.508 -0.3048)
			(stroke
				(width 0.1)
				(type default)
			)
			(layer "F.Fab")
		)
		(fp_line
			(start -0.508 -0.3048)
			(end -0.508 0.3048)
			(stroke
				(width 0.1)
				(type default)
			)
			(layer "F.Fab")
		)
		(fp_line
			(start 0.508 -0.3048)
			(end -0.508 -0.3048)
			(stroke
				(width 0.1)
				(type default)
			)
			(layer "F.Fab")
		)
		(pad "1" smd rect
			(at -0.5334 0 270)
			(size 0.7112 0.6096)
			(layers "F.Cu" "F.Mask" "F.Paste")
			(net "XP5R0V_USB_CONN")
		)
		(pad "2" smd rect
			(at 0.5334 0 270)
			(size 0.7112 0.6096)
			(layers "F.Cu" "F.Mask" "F.Paste")
			(net "SG")
		)
		(zone
			(layer "F.Cu")
			(hatch none 0.5)
			(connect_pads
				(clearance 0)
			)
			(min_thickness 0.25)
			(keepout
				(tracks allowed)
				(vias not_allowed)
				(pads allowed)
				(copperpour not_allowed)
				(footprints allowed)
			)
			(placement
				(enabled no)
				(sheetname "")
			)
			(fill
				(thermal_gap 0.5)
				(thermal_bridge_width 0.5)
				(island_removal_mode 0)
			)
			(polygon
				(pts
					(xy 160.0454 -50.513996) (xy 160.0454 -50.666396) (xy 159.4358 -50.666396) (xy 159.4358 -50.513996)
				)
			)
		)
	)
)
